# T6G (Grand Teton) — schematic netlist excerpt (pin names and nets, part order shuffled) for the footprints in the layout excerpt that follows; sources: Cadence DE-HDL packaged netlist, KiCad conversion of 04192023_DAF0TMB3IC0_F0TG_MB_C_brd_V02_OCP.brd

C2313  Q_CAP  22UF 4V 20% X6S  pkg C0402  page 73 : A = PVDDCR_CPU0_P1 ; B = GND
C322  Q_CAP  0.1UF 10V 10% X7S  pkg C0201  page 334 : A = P0V9_CPU1_RT1_2A ; B = GND
C2296  Q_CAP  22UF 4V 20% X6S  pkg C0402  page 73 : A = PVDDCR_CPU0_P1 ; B = GND

(kicad_pcb
	(version 20260206)
	(generator "pcbnew")
	(generator_version "10.0")
	(general
		(thickness 1.6)
		(legacy_teardrops no)
	)
	(paper "A4")
	(title_block
		(title "04192023_DAF0TMB3IC0_F0TG_MB_C_brd_V02_OCP.brd")
		(comment 1 "Grand Teton / footprints 5332-5334 of 8354")
	)
	(layers
		(0 "F.Cu" signal "TOP")
		(4 "In1.Cu" signal "GND")
		(6 "In2.Cu" signal "IN1")
		(8 "In3.Cu" signal "GND1")
		(10 "In4.Cu" signal "IN2")
		(12 "In5.Cu" signal "GND2")
		(14 "In6.Cu" signal "IN3")
		(16 "In7.Cu" signal "GND3")
		(18 "In8.Cu" signal "VCC")
		(20 "In9.Cu" signal "VCC1")
		(22 "In10.Cu" signal "GND4")
		(24 "In11.Cu" signal "IN4")
		(26 "In12.Cu" signal "GND5")
		(28 "In13.Cu" signal "IN5")
		(30 "In14.Cu" signal "GND6")
		(32 "In15.Cu" signal "IN6")
		(34 "In16.Cu" signal "GND7")
		(2 "B.Cu" signal "BOTTOM")
		(9 "F.Adhes" user "F.Adhesive")
		(11 "B.Adhes" user "B.Adhesive")
		(13 "F.Paste" user "Package Geometry/Pastemask Top")
		(15 "B.Paste" user "Package Geometry/Pastemask Bottom")
		(5 "F.SilkS" user "Ref Des/Silkscreen Top")
		(7 "B.SilkS" user "Ref Des/Silkscreen Bottom")
		(1 "F.Mask" user "Board Geometry/Soldermask Top")
		(3 "B.Mask" user "Board Geometry/Soldermask Bottom")
		(17 "Dwgs.User" user "User.Drawings")
		(19 "Cmts.User" user "User.Comments")
		(21 "Eco1.User" user "User.Eco1")
		(23 "Eco2.User" user "User.Eco2")
		(25 "Edge.Cuts" user "Board Geometry/Outline")
		(27 "Margin" user)
		(31 "F.CrtYd" user "Package Geometry/Place Bound Top")
		(29 "B.CrtYd" user "Package Geometry/Place Bound Bottom")
		(35 "F.Fab" user "Ref Des/Assembly Top")
		(33 "B.Fab" user "Ref Des/Assembly Bottom")
	)
	(footprint ""
		(layer "B.Cu")
		(at 119.801386 -250.892564)
		(property "Reference" "C2296"
			(at 0 0 0)
			(layer "B.SilkS")
			(hide yes)
			(effects
				(font
					(size 1.27 1.27)
				)
				(justify mirror)
			)
		)
		(property "Value" ""
			(at 0 0 0)
			(layer "B.Fab")
			(effects
				(font
					(size 1.27 1.27)
				)
				(justify mirror)
			)
		)
		(duplicate_pad_numbers_are_jumpers no)
		(fp_line
			(start -0.7874 -0.4064)
			(end -0.7874 0.4064)
			(stroke
				(width 0.1524)
				(type default)
			)
			(layer "B.SilkS")
		)
		(fp_line
			(start -0.7874 0.4064)
			(end 0.7874 0.4064)
			(stroke
				(width 0.1524)
				(type default)
			)
			(layer "B.SilkS")
		)
		(fp_line
			(start 0.7874 -0.4064)
			(end -0.7874 -0.4064)
			(stroke
				(width 0.1524)
				(type default)
			)
			(layer "B.SilkS")
		)
		(fp_line
			(start 0.7874 0.4064)
			(end 0.7874 -0.4064)
			(stroke
				(width 0.1524)
				(type default)
			)
			(layer "B.SilkS")
		)
		(fp_line
			(start -0.67945 -0.3048)
			(end -0.67945 0.3048)
			(stroke
				(width 0.1)
				(type default)
			)
			(layer "B.Fab")
		)
		(fp_line
			(start -0.67945 0.3048)
			(end -0.120396 0.3048)
			(stroke
				(width 0.1)
				(type default)
			)
			(layer "B.Fab")
		)
		(fp_line
			(start -0.12065 -0.3048)
			(end -0.67945 -0.3048)
			(stroke
				(width 0.1)
				(type default)
			)
			(layer "B.Fab")
		)
		(fp_line
			(start -0.12065 -0.2794)
			(end -0.12065 -0.3048)
			(stroke
				(width 0.1)
				(type default)
			)
			(layer "B.Fab")
		)
		(fp_line
			(start -0.120396 0.2794)
			(end 0.12065 0.2794)
			(stroke
				(width 0.1)
				(type default)
			)
			(layer "B.Fab")
		)
		(fp_line
			(start -0.120396 0.3048)
			(end -0.120396 0.2794)
			(stroke
				(width 0.1)
				(type default)
			)
			(layer "B.Fab")
		)
		(fp_line
			(start 0.12065 -0.305054)
			(end 0.12065 -0.2794)
			(stroke
				(width 0.1)
				(type default)
			)
			(layer "B.Fab")
		)
		(fp_line
			(start 0.12065 -0.2794)
			(end -0.12065 -0.2794)
			(stroke
				(width 0.1)
				(type default)
			)
			(layer "B.Fab")
		)
		(fp_line
			(start 0.12065 0.2794)
			(end 0.12065 0.3048)
			(stroke
				(width 0.1)
				(type default)
			)
			(layer "B.Fab")
		)
		(fp_line
			(start 0.12065 0.3048)
			(end 0.67945 0.3048)
			(stroke
				(width 0.1)
				(type default)
			)
			(layer "B.Fab")
		)
		(fp_line
			(start 0.67945 -0.305054)
			(end 0.12065 -0.305054)
			(stroke
				(width 0.1)
				(type default)
			)
			(layer "B.Fab")
		)
		(fp_line
			(start 0.67945 0.3048)
			(end 0.67945 -0.305054)
			(stroke
				(width 0.1)
				(type default)
			)
			(layer "B.Fab")
		)
		(pad "1" smd circle
			(at 0.40005 0 180)
			(size 0 0)
			(layers "B.Cu" "B.Mask" "B.Paste")
			(net "PVDDCR_CPU0_P1")
		)
		(pad "2" smd circle
			(at -0.40005 0 180)
			(size 0 0)
			(layers "B.Cu" "B.Mask" "B.Paste")
			(net "GND")
		)
	)
	(footprint ""
		(layer "B.Cu")
		(at 125.389386 -249.368564)
		(property "Reference" "C2313"
			(at 0 0 0)
			(layer "B.SilkS")
			(hide yes)
			(effects
				(font
					(size 1.27 1.27)
				)
				(justify mirror)
			)
		)
		(property "Value" ""
			(at 0 0 0)
			(layer "B.Fab")
			(effects
				(font
					(size 1.27 1.27)
				)
				(justify mirror)
			)
		)
		(duplicate_pad_numbers_are_jumpers no)
		(fp_line
			(start -0.7874 -0.4064)
			(end -0.7874 0.4064)
			(stroke
				(width 0.1524)
				(type default)
			)
			(layer "B.SilkS")
		)
		(fp_line
			(start -0.7874 0.4064)
			(end 0.7874 0.4064)
			(stroke
				(width 0.1524)
				(type default)
			)
			(layer "B.SilkS")
		)
		(fp_line
			(start 0.7874 -0.4064)
			(end -0.7874 -0.4064)
			(stroke
				(width 0.1524)
				(type default)
			)
			(layer "B.SilkS")
		)
		(fp_line
			(start 0.7874 0.4064)
			(end 0.7874 -0.4064)
			(stroke
				(width 0.1524)
				(type default)
			)
			(layer "B.SilkS")
		)
		(fp_line
			(start -0.67945 -0.3048)
			(end -0.67945 0.3048)
			(stroke
				(width 0.1)
				(type default)
			)
			(layer "B.Fab")
		)
		(fp_line
			(start -0.67945 0.3048)
			(end -0.120396 0.3048)
			(stroke
				(width 0.1)
				(type default)
			)
			(layer "B.Fab")
		)
		(fp_line
			(start -0.12065 -0.3048)
			(end -0.67945 -0.3048)
			(stroke
				(width 0.1)
				(type default)
			)
			(layer "B.Fab")
		)
		(fp_line
			(start -0.12065 -0.2794)
			(end -0.12065 -0.3048)
			(stroke
				(width 0.1)
				(type default)
			)
			(layer "B.Fab")
		)
		(fp_line
			(start -0.120396 0.2794)
			(end 0.12065 0.2794)
			(stroke
				(width 0.1)
				(type default)
			)
			(layer "B.Fab")
		)
		(fp_line
			(start -0.120396 0.3048)
			(end -0.120396 0.2794)
			(stroke
				(width 0.1)
				(type default)
			)
			(layer "B.Fab")
		)
		(fp_line
			(start 0.12065 -0.305054)
			(end 0.12065 -0.2794)
			(stroke
				(width 0.1)
				(type default)
			)
			(layer "B.Fab")
		)
		(fp_line
			(start 0.12065 -0.2794)
			(end -0.12065 -0.2794)
			(stroke
				(width 0.1)
				(type default)
			)
			(layer "B.Fab")
		)
		(fp_line
			(start 0.12065 0.2794)
			(end 0.12065 0.3048)
			(stroke
				(width 0.1)
				(type default)
			)
			(layer "B.Fab")
		)
		(fp_line
			(start 0.12065 0.3048)
			(end 0.67945 0.3048)
			(stroke
				(width 0.1)
				(type default)
			)
			(layer "B.Fab")
		)
		(fp_line
			(start 0.67945 -0.305054)
			(end 0.12065 -0.305054)
			(stroke
				(width 0.1)
				(type default)
			)
			(layer "B.Fab")
		)
		(fp_line
			(start 0.67945 0.3048)
			(end 0.67945 -0.305054)
			(stroke
				(width 0.1)
				(type default)
			)
			(layer "B.Fab")
		)
		(pad "1" smd circle
			(at 0.40005 0 180)
			(size 0 0)
			(layers "B.Cu" "B.Mask" "B.Paste")
			(net "PVDDCR_CPU0_P1")
		)
		(pad "2" smd circle
			(at -0.40005 0 180)
			(size 0 0)
			(layers "B.Cu" "B.Mask" "B.Paste")
			(net "GND")
		)
	)
	(footprint ""
		(layer "B.Cu")
		(at 81.246218 -388.011162 -90)
		(property "Reference" "C322"
			(at 0 0 90)
			(layer "B.SilkS")
			(hide yes)
			(effects
				(font
					(size 1.27 1.27)
				)
				(justify mirror)
			)
		)
		(property "Value" ""
			(at 0 0 90)
			(layer "B.Fab")
			(effects
				(font
					(size 1.27 1.27)
				)
				(justify mirror)
			)
		)
		(duplicate_pad_numbers_are_jumpers no)
		(fp_line
			(start -0.299974 0.150114)
			(end 0.299974 0.150114)
			(stroke
				(width 0.1)
				(type default)
			)
			(layer "B.Fab")
		)
		(fp_line
			(start 0.299974 0.150114)
			(end 0.299974 -0.150114)
			(stroke
				(width 0.1)
				(type default)
			)
			(layer "B.Fab")
		)
		(fp_line
			(start -0.299974 -0.150114)
			(end -0.299974 0.150114)
			(stroke
				(width 0.1)
				(type default)
			)
			(layer "B.Fab")
		)
		(fp_line
			(start 0.299974 -0.150114)
			(end -0.299974 -0.150114)
			(stroke
				(width 0.1)
				(type default)
			)
			(layer "B.Fab")
		)
		(pad "1" smd rect
			(at 0.2667 0 90)
			(size 0.3048 0.381)
			(layers "B.Cu" "B.Mask" "B.Paste")
			(net "P0V9_CPU1_RT1_2A")
		)
		(pad "2" smd rect
			(at -0.2667 0 90)
			(size 0.3048 0.381)
			(layers "B.Cu" "B.Mask" "B.Paste")
			(net "GND")
		)
	)
)
